#ISCELL
  pure_quanta quanta_title_block_c *
  *
#ISCELL
  standard offpage *
  page47_i1
#ISCELL
  standard offpage *
  page47_i10
#ISCELL
  standard offpage *
  page47_i11
#CELL
  pure_quanta socket4677_azif0045p001c01cs *
  page47_i16
#ISCELL
  standard offpage *
  page47_i2
#CELL
  pure_quanta q_res *
  page47_i22
#CELL
  pure_quanta q_res *
  page47_i23
#CELL
  pure_quanta q_res *
  page47_i24
#CELL
  pure_quanta q_res *
  page47_i25
#ISCELL
  standard offpage *
  page47_i26
#ISCELL
  standard offpage *
  page47_i3
#ISCELL
  standard offpage *
  page47_i30
#ISCELL
  standard offpage *
  page47_i31
#ISCELL
  standard offpage *
  page47_i32
#ISCELL
  standard offpage *
  page47_i33
#CELL
  pure_quanta q_res *
  page47_i34
#CELL
  pure_quanta q_res *
  page47_i35
#ISCELL
  logical_power universal_power *
  page47_i36
#ISCELL
  standard offpage *
  page47_i4
#ISCELL
  standard offpage *
  page47_i5
#ISCELL
  standard offpage *
  page47_i6
#ISCELL
  standard offpage *
  page47_i7
#ISCELL
  standard offpage *
  page47_i8
#ISCELL
  standard offpage *
  page47_i9
